# T6G (Grand Teton) — schematic netlist excerpt (pin names and nets, part order shuffled) for the footprints in the layout excerpt that follows; sources: Cadence DE-HDL packaged netlist, KiCad conversion of 04192023_DAF0TMB3IC0_F0TG_MB_C_brd_V02_OCP.brd

PR3840  Q_RES  71.5K 1% EMPTY  pkg 0402LF  page 135 : A = P12V_OCP_SFF ; B = P12V_OCP_OV_FB_1
D73  Q_LED  IC  pkg SMLF  page 255 : A = LED_PWRGD_PVDD33_S5_R ; C = LED_PWRGD_PVDD33_S5_D
C846  Q_CAP_DIFFBUS  DIFF BUS_0.22UF 6.3V 20% X6S  pkg C0201  page 64 : \1\ = P5E_CPU0_P2_TX_C_DN<11> ; \2\ = P5E_CPU0_P2_TX_DN<11>

(kicad_pcb
	(version 20260206)
	(generator "pcbnew")
	(generator_version "10.0")
	(general
		(thickness 1.6)
		(legacy_teardrops no)
	)
	(paper "A4")
	(title_block
		(title "04192023_DAF0TMB3IC0_F0TG_MB_C_brd_V02_OCP.brd")
		(comment 1 "Grand Teton / footprints 3568-3570 of 8354")
	)
	(layers
		(0 "F.Cu" signal "TOP")
		(4 "In1.Cu" signal "GND")
		(6 "In2.Cu" signal "IN1")
		(8 "In3.Cu" signal "GND1")
		(10 "In4.Cu" signal "IN2")
		(12 "In5.Cu" signal "GND2")
		(14 "In6.Cu" signal "IN3")
		(16 "In7.Cu" signal "GND3")
		(18 "In8.Cu" signal "VCC")
		(20 "In9.Cu" signal "VCC1")
		(22 "In10.Cu" signal "GND4")
		(24 "In11.Cu" signal "IN4")
		(26 "In12.Cu" signal "GND5")
		(28 "In13.Cu" signal "IN5")
		(30 "In14.Cu" signal "GND6")
		(32 "In15.Cu" signal "IN6")
		(34 "In16.Cu" signal "GND7")
		(2 "B.Cu" signal "BOTTOM")
		(9 "F.Adhes" user "F.Adhesive")
		(11 "B.Adhes" user "B.Adhesive")
		(13 "F.Paste" user "Package Geometry/Pastemask Top")
		(15 "B.Paste" user "Package Geometry/Pastemask Bottom")
		(5 "F.SilkS" user "Ref Des/Silkscreen Top")
		(7 "B.SilkS" user "Ref Des/Silkscreen Bottom")
		(1 "F.Mask" user "Board Geometry/Soldermask Top")
		(3 "B.Mask" user "Board Geometry/Soldermask Bottom")
		(17 "Dwgs.User" user "User.Drawings")
		(19 "Cmts.User" user "User.Comments")
		(21 "Eco1.User" user "User.Eco1")
		(23 "Eco2.User" user "User.Eco2")
		(25 "Edge.Cuts" user "Board Geometry/Outline")
		(27 "Margin" user)
		(31 "F.CrtYd" user "Package Geometry/Place Bound Top")
		(29 "B.CrtYd" user "Package Geometry/Place Bound Bottom")
		(35 "F.Fab" user "Ref Des/Assembly Top")
		(33 "B.Fab" user "Ref Des/Assembly Bottom")
	)
	(footprint ""
		(layer "F.Cu")
		(at 419.95344 -381.41783 -90)
		(property "Reference" "C846"
			(at 0 0 270)
			(layer "F.SilkS")
			(hide yes)
			(effects
				(font
					(size 1.27 1.27)
				)
			)
		)
		(property "Value" ""
			(at 0 0 270)
			(layer "F.Fab")
			(effects
				(font
					(size 1.27 1.27)
				)
			)
		)
		(duplicate_pad_numbers_are_jumpers no)
		(fp_line
			(start -0.299974 0.150114)
			(end -0.299974 -0.150114)
			(stroke
				(width 0.1)
				(type default)
			)
			(layer "F.Fab")
		)
		(fp_line
			(start 0.299974 0.150114)
			(end -0.299974 0.150114)
			(stroke
				(width 0.1)
				(type default)
			)
			(layer "F.Fab")
		)
		(fp_line
			(start -0.299974 -0.150114)
			(end 0.299974 -0.150114)
			(stroke
				(width 0.1)
				(type default)
			)
			(layer "F.Fab")
		)
		(fp_line
			(start 0.299974 -0.150114)
			(end 0.299974 0.150114)
			(stroke
				(width 0.1)
				(type default)
			)
			(layer "F.Fab")
		)
		(pad "1" smd rect
			(at -0.2667 0 270)
			(size 0.3048 0.381)
			(layers "F.Cu" "F.Mask" "F.Paste")
			(net "P5E_CPU0_P2_TX_C_DN<11>")
		)
		(pad "2" smd rect
			(at 0.2667 0 270)
			(size 0.3048 0.381)
			(layers "F.Cu" "F.Mask" "F.Paste")
			(net "P5E_CPU0_P2_TX_DN<11>")
		)
	)
	(footprint ""
		(layer "F.Cu")
		(at 322.603876 -70.098412 90)
		(property "Reference" "D73"
			(at -3.934714 -0.691642 90)
			(unlocked yes)
			(layer "F.SilkS")
			(effects
				(font
					(size 0.7874 0.5842)
					(thickness 0.1524)
				)
				(justify left)
			)
		)
		(property "Value" ""
			(at 0 0 90)
			(layer "F.Fab")
			(effects
				(font
					(size 1.27 1.27)
				)
			)
		)
		(duplicate_pad_numbers_are_jumpers no)
		(fp_line
			(start 1.16078 -0.4826)
			(end 1.16078 0.4826)
			(stroke
				(width 0.1524)
				(type default)
			)
			(layer "F.SilkS")
		)
		(fp_line
			(start 1.03378 -0.4826)
			(end 1.03378 0.4826)
			(stroke
				(width 0.1524)
				(type default)
			)
			(layer "F.SilkS")
		)
		(fp_line
			(start 0.90678 -0.4826)
			(end 0.90678 0.4826)
			(stroke
				(width 0.1524)
				(type default)
			)
			(layer "F.SilkS")
		)
		(fp_line
			(start -0.64008 -0.4826)
			(end 1.16078 -0.4826)
			(stroke
				(width 0.1524)
				(type default)
			)
			(layer "F.SilkS")
		)
		(fp_line
			(start -0.79248 -0.4826)
			(end 1.03378 -0.4826)
			(stroke
				(width 0.1524)
				(type default)
			)
			(layer "F.SilkS")
		)
		(fp_line
			(start -0.89408 -0.4826)
			(end 0.90678 -0.4826)
			(stroke
				(width 0.1524)
				(type default)
			)
			(layer "F.SilkS")
		)
		(fp_line
			(start 1.16078 0.4826)
			(end -0.64008 0.4826)
			(stroke
				(width 0.1524)
				(type default)
			)
			(layer "F.SilkS")
		)
		(fp_line
			(start 1.03378 0.4826)
			(end -0.79248 0.4826)
			(stroke
				(width 0.1524)
				(type default)
			)
			(layer "F.SilkS")
		)
		(fp_line
			(start 0.90678 0.4826)
			(end -0.90678 0.4826)
			(stroke
				(width 0.1524)
				(type default)
			)
			(layer "F.SilkS")
		)
		(fp_line
			(start -0.90678 0.4826)
			(end -0.90678 -0.4699)
			(stroke
				(width 0.1524)
				(type default)
			)
			(layer "F.SilkS")
		)
		(fp_line
			(start 0.499872 -0.249936)
			(end 0.499872 0.249936)
			(stroke
				(width 0.1)
				(type default)
			)
			(layer "F.Fab")
		)
		(fp_line
			(start -0.499872 -0.249936)
			(end 0.499872 -0.249936)
			(stroke
				(width 0.1)
				(type default)
			)
			(layer "F.Fab")
		)
		(fp_line
			(start 0.499872 0.249936)
			(end -0.499872 0.249936)
			(stroke
				(width 0.1)
				(type default)
			)
			(layer "F.Fab")
		)
		(fp_line
			(start -0.499872 0.249936)
			(end -0.499872 -0.249936)
			(stroke
				(width 0.1)
				(type default)
			)
			(layer "F.Fab")
		)
		(pad "A" smd rect
			(at -0.47498 0 90)
			(size 0.6096 0.7112)
			(layers "F.Cu" "F.Mask" "F.Paste")
			(net "LED_PWRGD_PVDD33_S5_R")
		)
		(pad "C" smd rect
			(at 0.47498 0 90)
			(size 0.6096 0.7112)
			(layers "F.Cu" "F.Mask" "F.Paste")
			(net "LED_PWRGD_PVDD33_S5_D")
		)
	)
	(footprint ""
		(layer "F.Cu")
		(at 436.526432 -26.056336 90)
		(property "Reference" "PR3840"
			(at 0 0 90)
			(layer "F.SilkS")
			(hide yes)
			(effects
				(font
					(size 1.27 1.27)
				)
			)
		)
		(property "Value" ""
			(at 0 0 90)
			(layer "F.Fab")
			(effects
				(font
					(size 1.27 1.27)
				)
			)
		)
		(duplicate_pad_numbers_are_jumpers no)
		(fp_line
			(start 0.7874 -0.4064)
			(end 0.7874 0.4064)
			(stroke
				(width 0.1524)
				(type default)
			)
			(layer "F.SilkS")
		)
		(fp_line
			(start -0.7874 -0.4064)
			(end 0.7874 -0.4064)
			(stroke
				(width 0.1524)
				(type default)
			)
			(layer "F.SilkS")
		)
		(fp_line
			(start 0.7874 0.4064)
			(end -0.7874 0.4064)
			(stroke
				(width 0.1524)
				(type default)
			)
			(layer "F.SilkS")
		)
		(fp_line
			(start -0.7874 0.4064)
			(end -0.7874 -0.4064)
			(stroke
				(width 0.1524)
				(type default)
			)
			(layer "F.SilkS")
		)
		(fp_line
			(start -0.12065 -0.305054)
			(end -0.12065 -0.2794)
			(stroke
				(width 0.1)
				(type default)
			)
			(layer "F.Fab")
		)
		(fp_line
			(start -0.67945 -0.305054)
			(end -0.12065 -0.305054)
			(stroke
				(width 0.1)
				(type default)
			)
			(layer "F.Fab")
		)
		(fp_line
			(start 0.67945 -0.3048)
			(end 0.67945 0.3048)
			(stroke
				(width 0.1)
				(type default)
			)
			(layer "F.Fab")
		)
		(fp_line
			(start 0.12065 -0.3048)
			(end 0.67945 -0.3048)
			(stroke
				(width 0.1)
				(type default)
			)
			(layer "F.Fab")
		)
		(fp_line
			(start 0.12065 -0.2794)
			(end 0.12065 -0.3048)
			(stroke
				(width 0.1)
				(type default)
			)
			(layer "F.Fab")
		)
		(fp_line
			(start -0.12065 -0.2794)
			(end 0.12065 -0.2794)
			(stroke
				(width 0.1)
				(type default)
			)
			(layer "F.Fab")
		)
		(fp_line
			(start 0.120396 0.2794)
			(end -0.12065 0.2794)
			(stroke
				(width 0.1)
				(type default)
			)
			(layer "F.Fab")
		)
		(fp_line
			(start -0.12065 0.2794)
			(end -0.12065 0.3048)
			(stroke
				(width 0.1)
				(type default)
			)
			(layer "F.Fab")
		)
		(fp_line
			(start 0.67945 0.3048)
			(end 0.120396 0.3048)
			(stroke
				(width 0.1)
				(type default)
			)
			(layer "F.Fab")
		)
		(fp_line
			(start 0.120396 0.3048)
			(end 0.120396 0.2794)
			(stroke
				(width 0.1)
				(type default)
			)
			(layer "F.Fab")
		)
		(fp_line
			(start -0.12065 0.3048)
			(end -0.67945 0.3048)
			(stroke
				(width 0.1)
				(type default)
			)
			(layer "F.Fab")
		)
		(fp_line
			(start -0.67945 0.3048)
			(end -0.67945 -0.305054)
			(stroke
				(width 0.1)
				(type default)
			)
			(layer "F.Fab")
		)
		(pad "1" smd circle
			(at -0.40005 0 90)
			(size 0 0)
			(layers "F.Cu" "F.Mask" "F.Paste")
			(net "P12V_OCP_SFF")
		)
		(pad "2" smd circle
			(at 0.40005 0 90)
			(size 0 0)
			(layers "F.Cu" "F.Mask" "F.Paste")
			(net "P12V_OCP_OV_FB_1")
		)
	)
)
